(kicad_pcb
	(version 20241229)
	(generator "pcbnew")
	(generator_version "9.0")
	(general
		(thickness 1.62)
		(legacy_teardrops no)
	)
	(paper "A3")
	(title_block
		(title "COM Express 7 Baseboard")
		(date "2025-02-04")
		(rev "1.1.2")
		(company "Antmicro Ltd")
		(comment 1 "www.antmicro.com")
		(comment 9 "footprints 112-112 of 802")
	)
	(layers
		(0 "F.Cu" signal)
		(4 "In1.Cu" signal)
		(6 "In2.Cu" signal)
		(8 "In3.Cu" signal)
		(10 "In4.Cu" signal)
		(12 "In5.Cu" signal)
		(14 "In6.Cu" signal)
		(2 "B.Cu" signal)
		(9 "F.Adhes" user "F.Adhesive")
		(11 "B.Adhes" user "B.Adhesive")
		(13 "F.Paste" user)
		(15 "B.Paste" user)
		(5 "F.SilkS" user "F.Silkscreen")
		(7 "B.SilkS" user "B.Silkscreen")
		(1 "F.Mask" user)
		(3 "B.Mask" user)
		(17 "Dwgs.User" user "User.Drawings")
		(19 "Cmts.User" user "User.Comments")
		(21 "Eco1.User" user "User.Eco1")
		(23 "Eco2.User" user "User.Eco2")
		(25 "Edge.Cuts" user)
		(27 "Margin" user)
		(31 "F.CrtYd" user "F.Courtyard")
		(29 "B.CrtYd" user "B.Courtyard")
		(35 "F.Fab" user)
		(33 "B.Fab" user)
	)
	(footprint "antmicro-footprints:SOT-23-8"
		(layer "F.Cu")
		(at 244.05 129.26 -90)
		(descr "http://www.ti.com/lit/ds/symlink/ina219.pdf")
		(property "Reference" "U34"
			(at 1.4 1.7 180)
			(layer "F.SilkS")
			(effects
				(font
					(size 0.7 0.7)
					(thickness 0.15)
				)
				(justify right bottom)
			)
		)
		(property "Value" "LTC2950CTS8-1"
			(at 0 2.8 90)
			(layer "F.Fab")
			(effects
				(font
					(size 0.7 0.7)
					(thickness 0.15)
				)
				(justify right bottom)
			)
		)
		(property "Datasheet" "https://www.analog.com/media/en/technical-documentation/data-sheets/295012fd.pdf"
			(at 0 0 270)
			(layer "F.Fab")
			(hide yes)
			(effects
				(font
					(size 1.27 1.27)
					(thickness 0.15)
				)
			)
		)
		(property "Author" "Antmicro"
			(at 114.79 373.31 0)
			(layer "F.Fab")
			(hide yes)
			(effects
				(font
					(size 1 1)
					(thickness 0.15)
				)
			)
		)
		(property "License" "Apache-2.0"
			(at 114.79 373.31 0)
			(layer "F.Fab")
			(hide yes)
			(effects
				(font
					(size 1 1)
					(thickness 0.15)
				)
			)
		)
		(property "MPN" "LTC2950CTS8-1"
			(at 114.79 373.31 0)
			(layer "F.Fab")
			(hide yes)
			(effects
				(font
					(size 1 1)
					(thickness 0.15)
				)
			)
		)
		(property "Manufacturer" "Analog Devices"
			(at 114.79 373.31 0)
			(layer "F.Fab")
			(hide yes)
			(effects
				(font
					(size 1 1)
					(thickness 0.15)
				)
			)
		)
		(sheetname "Com Express 7 MGMT")
		(sheetfile "com_express_7_mgmt.kicad_sch")
		(attr smd)
		(fp_line
			(start -0.987 1.6)
			(end -0.987 1.324)
			(stroke
				(width 0.15)
				(type solid)
			)
			(layer "F.SilkS")
		)
		(fp_line
			(start -0.613 1.6)
			(end -0.987 1.6)
			(stroke
				(width 0.15)
				(type solid)
			)
			(layer "F.SilkS")
		)
		(fp_line
			(start 1 1.6)
			(end 0.6 1.6)
			(stroke
				(width 0.15)
				(type solid)
			)
			(layer "F.SilkS")
		)
		(fp_line
			(start 1 1.3)
			(end 1 1.6)
			(stroke
				(width 0.15)
				(type solid)
			)
			(layer "F.SilkS")
		)
		(fp_line
			(start -1 -1.3)
			(end -1 -1.6)
			(stroke
				(width 0.15)
				(type solid)
			)
			(layer "F.SilkS")
		)
		(fp_line
			(start 1 -1.3)
			(end 1 -1.6)
			(stroke
				(width 0.15)
				(type solid)
			)
			(layer "F.SilkS")
		)
		(fp_line
			(start -1 -1.6)
			(end -0.6 -1.6)
			(stroke
				(width 0.15)
				(type solid)
			)
			(layer "F.SilkS")
		)
		(fp_line
			(start 1 -1.6)
			(end 0.625 -1.6)
			(stroke
				(width 0.15)
				(type solid)
			)
			(layer "F.SilkS")
		)
		(fp_circle
			(center -1.3 -1.4)
			(end -1.25 -1.4)
			(stroke
				(width 0.15)
				(type solid)
			)
			(fill yes)
			(layer "F.SilkS")
		)
		(fp_rect
			(start -1.9 -1.75)
			(end 1.898 1.75)
			(stroke
				(width 0.05)
				(type solid)
			)
			(fill no)
			(layer "F.CrtYd")
		)
		(fp_line
			(start -1.4 -1.25)
			(end -1.2 -1.45)
			(stroke
				(width 0.15)
				(type solid)
			)
			(layer "F.Fab")
		)
		(fp_rect
			(start -1.401 -1.45)
			(end 1.398 1.449)
			(stroke
				(width 0.15)
				(type solid)
			)
			(fill no)
			(layer "F.Fab")
		)
		(pad "1" smd roundrect
			(at -1.3 -0.975 180)
			(size 0.45 1.1)
			(layers "F.Cu" "F.Mask" "F.Paste")
			(roundrect_rratio 0.25)
			(net 73 "+3V3_AON")
			(pinfunction "V_{IN}")
			(pintype "power_in")
			(teardrops
				(best_length_ratio 0.2)
				(max_length 1)
				(best_width_ratio 0.9)
				(max_width 2)
				(curved_edges yes)
				(filter_ratio 0.9)
				(enabled yes)
				(allow_two_segments yes)
				(prefer_zone_connections yes)
			)
		)
		(pad "2" smd roundrect
			(at -1.3 -0.325 180)
			(size 0.45 1.1)
			(layers "F.Cu" "F.Mask" "F.Paste")
			(roundrect_rratio 0.25)
			(net 84 "/Com Express 7 MGMT/PWRBTN")
			(pinfunction "~{PB}")
			(pintype "input")
			(teardrops
				(best_length_ratio 0.2)
				(max_length 1)
				(best_width_ratio 0.9)
				(max_width 2)
				(curved_edges yes)
				(filter_ratio 0.9)
				(enabled yes)
				(allow_two_segments yes)
				(prefer_zone_connections yes)
			)
		)
		(pad "3" smd roundrect
			(at -1.3 0.325 180)
			(size 0.45 1.1)
			(layers "F.Cu" "F.Mask" "F.Paste")
			(roundrect_rratio 0.25)
			(net 48 "Net-(U34-ONT)")
			(pinfunction "ONT")
			(pintype "passive")
			(teardrops
				(best_length_ratio 0.2)
				(max_length 1)
				(best_width_ratio 0.9)
				(max_width 2)
				(curved_edges yes)
				(filter_ratio 0.9)
				(enabled yes)
				(allow_two_segments yes)
				(prefer_zone_connections yes)
			)
		)
		(pad "4" smd roundrect
			(at -1.3 0.975 180)
			(size 0.45 1.1)
			(layers "F.Cu" "F.Mask" "F.Paste")
			(roundrect_rratio 0.25)
			(net 1 "GND")
			(pinfunction "GND")
			(pintype "power_in")
			(teardrops
				(best_length_ratio 0.2)
				(max_length 1)
				(best_width_ratio 0.9)
				(max_width 2)
				(curved_edges yes)
				(filter_ratio 0.9)
				(enabled yes)
				(allow_two_segments yes)
				(prefer_zone_connections yes)
			)
		)
		(pad "5" smd roundrect
			(at 1.3 0.975 180)
			(size 0.45 1.1)
			(layers "F.Cu" "F.Mask" "F.Paste")
			(roundrect_rratio 0.25)
			(net 599 "Net-(U34-~{INT})")
			(pinfunction "~{INT}")
			(pintype "output")
			(teardrops
				(best_length_ratio 0.2)
				(max_length 1)
				(best_width_ratio 0.9)
				(max_width 2)
				(curved_edges yes)
				(filter_ratio 0.9)
				(enabled yes)
				(allow_two_segments yes)
				(prefer_zone_connections yes)
			)
		)
		(pad "6" smd roundrect
			(at 1.3 0.325 180)
			(size 0.45 1.1)
			(layers "F.Cu" "F.Mask" "F.Paste")
			(roundrect_rratio 0.25)
			(net 873 "Net-(U34-EN)")
			(pinfunction "EN")
			(pintype "output")
			(teardrops
				(best_length_ratio 0.2)
				(max_length 1)
				(best_width_ratio 0.9)
				(max_width 2)
				(curved_edges yes)
				(filter_ratio 0.9)
				(enabled yes)
				(allow_two_segments yes)
				(prefer_zone_connections yes)
			)
		)
		(pad "7" smd roundrect
			(at 1.3 -0.325 180)
			(size 0.45 1.1)
			(layers "F.Cu" "F.Mask" "F.Paste")
			(roundrect_rratio 0.25)
			(net 46 "Net-(U34-OFFT)")
			(pinfunction "OFFT")
			(pintype "passive")
			(teardrops
				(best_length_ratio 0.2)
				(max_length 1)
				(best_width_ratio 0.9)
				(max_width 2)
				(curved_edges yes)
				(filter_ratio 0.9)
				(enabled yes)
				(allow_two_segments yes)
				(prefer_zone_connections yes)
			)
		)
		(pad "8" smd roundrect
			(at 1.3 -0.975 180)
			(size 0.45 1.1)
			(layers "F.Cu" "F.Mask" "F.Paste")
			(roundrect_rratio 0.25)
			(net 872 "Net-(U34-~{KILL})")
			(pinfunction "~{KILL}")
			(pintype "input")
			(teardrops
				(best_length_ratio 0.2)
				(max_length 1)
				(best_width_ratio 0.9)
				(max_width 2)
				(curved_edges yes)
				(filter_ratio 0.9)
				(enabled yes)
				(allow_two_segments yes)
				(prefer_zone_connections yes)
			)
		)
	)
)
